# S9S_MB_2U (Grand Teton) — schematic netlist excerpt (pin names and nets, part order shuffled) for the footprints in the layout excerpt that follows; sources: Cadence DE-HDL packaged netlist, KiCad conversion of 03242023_DA0F0TMBIJ0_F0T_Motherboard_J_brd_V01_OCP.brd

C1311  Q_CAP  1UF 25V 10% X6S  pkg C0402  page 210 : A = P3V3_AUX_CLK_GEN_VDDXTAL_CK440 ; B = GND
PC284_P0_4  Q_CAP  22UF 16V 20% X6S  pkg C0805  page 268 : A = SW_P12V_PVCCIN_CPU0_FLT ; B = GND
PR403  Q_RES  0 5% EMPTY  pkg 0402LF  page 267 : A = P3V3 ; B = PVCCIN_CPU0_PVCC

(kicad_pcb
	(version 20260206)
	(generator "pcbnew")
	(generator_version "10.0")
	(general
		(thickness 1.6)
		(legacy_teardrops no)
	)
	(paper "A4")
	(title_block
		(title "03242023_DA0F0TMBIJ0_F0T_Motherboard_J_brd_V01_OCP.brd")
		(comment 1 "Grand Teton / footprints 4657-4659 of 6105")
	)
	(layers
		(0 "F.Cu" signal "TOP")
		(4 "In1.Cu" signal "GND")
		(6 "In2.Cu" signal "IN1")
		(8 "In3.Cu" signal "GND1")
		(10 "In4.Cu" signal "IN2")
		(12 "In5.Cu" signal "GND2")
		(14 "In6.Cu" signal "IN3")
		(16 "In7.Cu" signal "GND3")
		(18 "In8.Cu" signal "VCC")
		(20 "In9.Cu" signal "VCC1")
		(22 "In10.Cu" signal "GND4")
		(24 "In11.Cu" signal "IN4")
		(26 "In12.Cu" signal "GND5")
		(28 "In13.Cu" signal "IN5")
		(30 "In14.Cu" signal "GND6")
		(32 "In15.Cu" signal "IN6")
		(34 "In16.Cu" signal "GND7")
		(2 "B.Cu" signal "BOTTOM")
		(9 "F.Adhes" user "F.Adhesive")
		(11 "B.Adhes" user "B.Adhesive")
		(13 "F.Paste" user "Package Geometry/Pastemask Top")
		(15 "B.Paste" user "Package Geometry/Pastemask Bottom")
		(5 "F.SilkS" user "Ref Des/Silkscreen Top")
		(7 "B.SilkS" user "Ref Des/Silkscreen Bottom")
		(1 "F.Mask" user "Board Geometry/Soldermask Top")
		(3 "B.Mask" user "Board Geometry/Soldermask Bottom")
		(17 "Dwgs.User" user "User.Drawings")
		(19 "Cmts.User" user "User.Comments")
		(21 "Eco1.User" user "User.Eco1")
		(23 "Eco2.User" user "User.Eco2")
		(25 "Edge.Cuts" user "Board Geometry/Outline")
		(27 "Margin" user)
		(31 "F.CrtYd" user "Package Geometry/Place Bound Top")
		(29 "B.CrtYd" user "Package Geometry/Place Bound Bottom")
		(35 "F.Fab" user "Ref Des/Assembly Top")
		(33 "B.Fab" user "Ref Des/Assembly Bottom")
	)
	(footprint ""
		(layer "B.Cu")
		(at 252.222 -98.389948 180)
		(property "Reference" "C1311"
			(at 0 0 0)
			(layer "B.SilkS")
			(hide yes)
			(effects
				(font
					(size 1.27 1.27)
				)
				(justify mirror)
			)
		)
		(property "Value" ""
			(at 0 0 0)
			(layer "B.Fab")
			(effects
				(font
					(size 1.27 1.27)
				)
				(justify mirror)
			)
		)
		(duplicate_pad_numbers_are_jumpers no)
		(fp_line
			(start 0.7874 0.4064)
			(end 0.7874 -0.4064)
			(stroke
				(width 0.1524)
				(type default)
			)
			(layer "B.SilkS")
		)
		(fp_line
			(start 0.7874 -0.4064)
			(end -0.7874 -0.4064)
			(stroke
				(width 0.1524)
				(type default)
			)
			(layer "B.SilkS")
		)
		(fp_line
			(start -0.7874 0.4064)
			(end 0.7874 0.4064)
			(stroke
				(width 0.1524)
				(type default)
			)
			(layer "B.SilkS")
		)
		(fp_line
			(start -0.7874 -0.4064)
			(end -0.7874 0.4064)
			(stroke
				(width 0.1524)
				(type default)
			)
			(layer "B.SilkS")
		)
		(fp_line
			(start 0.67945 0.3048)
			(end 0.67945 -0.305054)
			(stroke
				(width 0.1)
				(type default)
			)
			(layer "B.Fab")
		)
		(fp_line
			(start 0.67945 -0.305054)
			(end 0.12065 -0.305054)
			(stroke
				(width 0.1)
				(type default)
			)
			(layer "B.Fab")
		)
		(fp_line
			(start 0.12065 0.3048)
			(end 0.67945 0.3048)
			(stroke
				(width 0.1)
				(type default)
			)
			(layer "B.Fab")
		)
		(fp_line
			(start 0.12065 0.2794)
			(end 0.12065 0.3048)
			(stroke
				(width 0.1)
				(type default)
			)
			(layer "B.Fab")
		)
		(fp_line
			(start 0.12065 -0.2794)
			(end -0.12065 -0.2794)
			(stroke
				(width 0.1)
				(type default)
			)
			(layer "B.Fab")
		)
		(fp_line
			(start 0.12065 -0.305054)
			(end 0.12065 -0.2794)
			(stroke
				(width 0.1)
				(type default)
			)
			(layer "B.Fab")
		)
		(fp_line
			(start -0.120396 0.3048)
			(end -0.120396 0.2794)
			(stroke
				(width 0.1)
				(type default)
			)
			(layer "B.Fab")
		)
		(fp_line
			(start -0.120396 0.2794)
			(end 0.12065 0.2794)
			(stroke
				(width 0.1)
				(type default)
			)
			(layer "B.Fab")
		)
		(fp_line
			(start -0.12065 -0.2794)
			(end -0.12065 -0.3048)
			(stroke
				(width 0.1)
				(type default)
			)
			(layer "B.Fab")
		)
		(fp_line
			(start -0.12065 -0.3048)
			(end -0.67945 -0.3048)
			(stroke
				(width 0.1)
				(type default)
			)
			(layer "B.Fab")
		)
		(fp_line
			(start -0.67945 0.3048)
			(end -0.120396 0.3048)
			(stroke
				(width 0.1)
				(type default)
			)
			(layer "B.Fab")
		)
		(fp_line
			(start -0.67945 -0.3048)
			(end -0.67945 0.3048)
			(stroke
				(width 0.1)
				(type default)
			)
			(layer "B.Fab")
		)
		(pad "1" smd circle
			(at 0.40005 0)
			(size 0 0)
			(layers "B.Cu" "B.Mask" "B.Paste")
			(net "P3V3_AUX_CLK_GEN_VDDXTAL_CK440")
		)
		(pad "2" smd circle
			(at -0.40005 0)
			(size 0 0)
			(layers "B.Cu" "B.Mask" "B.Paste")
			(net "GND")
		)
	)
	(footprint ""
		(layer "B.Cu")
		(at 370.540788 -333.73568 90)
		(property "Reference" "PC284_P0_4"
			(at 0 0 90)
			(layer "B.SilkS")
			(hide yes)
			(effects
				(font
					(size 1.27 1.27)
				)
				(justify mirror)
			)
		)
		(property "Value" ""
			(at 0 0 90)
			(layer "B.Fab")
			(effects
				(font
					(size 1.27 1.27)
				)
				(justify mirror)
			)
		)
		(duplicate_pad_numbers_are_jumpers no)
		(fp_line
			(start 1.524 -0.762)
			(end -1.524 -0.762)
			(stroke
				(width 0.1524)
				(type default)
			)
			(layer "B.SilkS")
		)
		(fp_line
			(start -1.524 -0.762)
			(end -1.524 0.762)
			(stroke
				(width 0.1524)
				(type default)
			)
			(layer "B.SilkS")
		)
		(fp_line
			(start 1.524 0.762)
			(end 1.524 -0.762)
			(stroke
				(width 0.1524)
				(type default)
			)
			(layer "B.SilkS")
		)
		(fp_line
			(start -1.524 0.762)
			(end 1.524 0.762)
			(stroke
				(width 0.1524)
				(type default)
			)
			(layer "B.SilkS")
		)
		(fp_line
			(start 1.1049 -0.724916)
			(end 1.1049 0.724916)
			(stroke
				(width 0.1)
				(type default)
			)
			(layer "B.Fab")
		)
		(fp_line
			(start -1.1049 -0.724916)
			(end 1.1049 -0.724916)
			(stroke
				(width 0.1)
				(type default)
			)
			(layer "B.Fab")
		)
		(fp_line
			(start 1.1049 0.724916)
			(end -1.1049 0.724916)
			(stroke
				(width 0.1)
				(type default)
			)
			(layer "B.Fab")
		)
		(fp_line
			(start -1.1049 0.724916)
			(end -1.1049 -0.724916)
			(stroke
				(width 0.1)
				(type default)
			)
			(layer "B.Fab")
		)
		(pad "1" smd rect
			(at 0.889 0 90)
			(size 1.016 1.27)
			(layers "B.Cu" "B.Mask" "B.Paste")
			(net "SW_P12V_PVCCIN_CPU0_FLT")
		)
		(pad "2" smd rect
			(at -0.889 0 90)
			(size 1.016 1.27)
			(layers "B.Cu" "B.Mask" "B.Paste")
			(net "GND")
		)
	)
	(footprint ""
		(layer "B.Cu")
		(at 324.067424 -343.927938 90)
		(property "Reference" "PR403"
			(at 0 0 90)
			(layer "B.SilkS")
			(hide yes)
			(effects
				(font
					(size 1.27 1.27)
				)
				(justify mirror)
			)
		)
		(property "Value" ""
			(at 0 0 90)
			(layer "B.Fab")
			(effects
				(font
					(size 1.27 1.27)
				)
				(justify mirror)
			)
		)
		(duplicate_pad_numbers_are_jumpers no)
		(fp_line
			(start 0.7874 -0.4064)
			(end -0.7874 -0.4064)
			(stroke
				(width 0.1524)
				(type default)
			)
			(layer "B.SilkS")
		)
		(fp_line
			(start -0.7874 -0.4064)
			(end -0.7874 0.4064)
			(stroke
				(width 0.1524)
				(type default)
			)
			(layer "B.SilkS")
		)
		(fp_line
			(start 0.7874 0.4064)
			(end 0.7874 -0.4064)
			(stroke
				(width 0.1524)
				(type default)
			)
			(layer "B.SilkS")
		)
		(fp_line
			(start -0.7874 0.4064)
			(end 0.7874 0.4064)
			(stroke
				(width 0.1524)
				(type default)
			)
			(layer "B.SilkS")
		)
		(fp_line
			(start 0.67945 -0.305054)
			(end 0.12065 -0.305054)
			(stroke
				(width 0.1)
				(type default)
			)
			(layer "B.Fab")
		)
		(fp_line
			(start 0.12065 -0.305054)
			(end 0.12065 -0.2794)
			(stroke
				(width 0.1)
				(type default)
			)
			(layer "B.Fab")
		)
		(fp_line
			(start -0.12065 -0.3048)
			(end -0.67945 -0.3048)
			(stroke
				(width 0.1)
				(type default)
			)
			(layer "B.Fab")
		)
		(fp_line
			(start -0.67945 -0.3048)
			(end -0.67945 0.3048)
			(stroke
				(width 0.1)
				(type default)
			)
			(layer "B.Fab")
		)
		(fp_line
			(start 0.12065 -0.2794)
			(end -0.12065 -0.2794)
			(stroke
				(width 0.1)
				(type default)
			)
			(layer "B.Fab")
		)
		(fp_line
			(start -0.12065 -0.2794)
			(end -0.12065 -0.3048)
			(stroke
				(width 0.1)
				(type default)
			)
			(layer "B.Fab")
		)
		(fp_line
			(start 0.12065 0.2794)
			(end 0.12065 0.3048)
			(stroke
				(width 0.1)
				(type default)
			)
			(layer "B.Fab")
		)
		(fp_line
			(start -0.120396 0.2794)
			(end 0.12065 0.2794)
			(stroke
				(width 0.1)
				(type default)
			)
			(layer "B.Fab")
		)
		(fp_line
			(start 0.67945 0.3048)
			(end 0.67945 -0.305054)
			(stroke
				(width 0.1)
				(type default)
			)
			(layer "B.Fab")
		)
		(fp_line
			(start 0.12065 0.3048)
			(end 0.67945 0.3048)
			(stroke
				(width 0.1)
				(type default)
			)
			(layer "B.Fab")
		)
		(fp_line
			(start -0.120396 0.3048)
			(end -0.120396 0.2794)
			(stroke
				(width 0.1)
				(type default)
			)
			(layer "B.Fab")
		)
		(fp_line
			(start -0.67945 0.3048)
			(end -0.120396 0.3048)
			(stroke
				(width 0.1)
				(type default)
			)
			(layer "B.Fab")
		)
		(pad "1" smd circle
			(at 0.40005 0 270)
			(size 0 0)
			(layers "B.Cu" "B.Mask" "B.Paste")
			(net "P3V3")
		)
		(pad "2" smd circle
			(at -0.40005 0 270)
			(size 0 0)
			(layers "B.Cu" "B.Mask" "B.Paste")
			(net "PVCCIN_CPU0_PVCC")
		)
	)
)
